# BASEBOARD_FAB2 (Tioga Pass) — schematic netlist excerpt (pin names and nets, part order shuffled) for the footprints in the layout excerpt that follows; sources: Cadence DE-HDL packaged netlist, KiCad conversion of Wiwynn_Tioga_Pass_MB.brd

U32W2  TCA9517DGKR-GP  pkg DISCRET-G8  page 185
  VCCA  = P1V8_M2
  SCLA  = SMB_M2_ALT_R_N
  SDAA  = NC
  GND  = GND
  EN  = PD_SMB_M2_EN
  SDAB  = NC
  SCLB  = IRQ_MEZZ_LAN_ALERT_N
  VCCB  = P3V3_STBY

C9L3  CAP_A  0.01UF 25V 10% X7R  pkg 0402V  page 100 : A = M_M_CPU_VREF ; B = GND

(kicad_pcb
	(version 20260206)
	(generator "pcbnew")
	(generator_version "10.0")
	(general
		(thickness 1.6)
		(legacy_teardrops no)
	)
	(paper "A4")
	(title_block
		(title "Wiwynn_Tioga_Pass_MB.brd")
		(comment 1 "Tioga Pass / footprints 2353-2354 of 4770")
	)
	(layers
		(0 "F.Cu" signal "TOP")
		(4 "In1.Cu" signal "L2GND")
		(6 "In2.Cu" signal "L3")
		(8 "In3.Cu" signal "L4GND")
		(10 "In4.Cu" signal "L5")
		(12 "In5.Cu" signal "L6GND")
		(14 "In6.Cu" signal "L7VCC")
		(16 "In7.Cu" signal "L8VCC")
		(18 "In8.Cu" signal "L9GND")
		(20 "In9.Cu" signal "L10")
		(22 "In10.Cu" signal "L11GND")
		(24 "In11.Cu" signal "L12")
		(26 "In12.Cu" signal "L13GND")
		(2 "B.Cu" signal "BOTTOM")
		(9 "F.Adhes" user "F.Adhesive")
		(11 "B.Adhes" user "B.Adhesive")
		(13 "F.Paste" user "Package Geometry/Pastemask Top")
		(15 "B.Paste" user "Package Geometry/Pastemask Bottom")
		(5 "F.SilkS" user "Ref Des/Silkscreen Top")
		(7 "B.SilkS" user "Ref Des/Silkscreen Bottom")
		(1 "F.Mask" user "Board Geometry/Soldermask Top")
		(3 "B.Mask" user "Board Geometry/Soldermask Bottom")
		(17 "Dwgs.User" user "User.Drawings")
		(19 "Cmts.User" user "User.Comments")
		(21 "Eco1.User" user "User.Eco1")
		(23 "Eco2.User" user "User.Eco2")
		(25 "Edge.Cuts" user "Board Geometry/Outline")
		(27 "Margin" user)
		(31 "F.CrtYd" user "Package Geometry/Place Bound Top")
		(29 "B.CrtYd" user "Package Geometry/Place Bound Bottom")
		(35 "F.Fab" user "Ref Des/Assembly Top")
		(33 "B.Fab" user "Ref Des/Assembly Bottom")
	)
	(footprint ""
		(layer "B.Cu")
		(at 388.892542 -12.473432)
		(property "Reference" "U32W2"
			(at 0 0 0)
			(layer "B.SilkS")
			(hide yes)
			(effects
				(font
					(size 1.27 1.27)
				)
				(justify mirror)
			)
		)
		(property "Value" "*"
			(at 0.1143 -9.3091 0)
			(unlocked yes)
			(layer "B.Fab")
			(hide yes)
			(effects
				(font
					(size 1.27 1.016)
					(thickness 0.1524)
				)
				(justify mirror)
			)
		)
		(property "Device Type" "TCA9517DGKR-GP_DISCRET-G8-TCA9A"
			(at 0.1143 -10.9093 0)
			(unlocked yes)
			(layer "B.Fab")
			(hide yes)
			(effects
				(font
					(size 1.27 1.016)
					(thickness 0.1524)
				)
				(justify mirror)
			)
		)
		(duplicate_pad_numbers_are_jumpers no)
		(fp_line
			(start -1.0795 -1.016)
			(end 1.9558 -1.016)
			(stroke
				(width 0.1524)
				(type default)
			)
			(layer "B.SilkS")
		)
		(fp_line
			(start -1.0795 1.016)
			(end -1.0795 -1.016)
			(stroke
				(width 0.1524)
				(type default)
			)
			(layer "B.SilkS")
		)
		(fp_line
			(start 1.4478 -0.0381)
			(end 1.9558 0.4699)
			(stroke
				(width 0.1524)
				(type default)
			)
			(layer "B.SilkS")
		)
		(fp_line
			(start 1.778 1.0922)
			(end 1.778 3.048)
			(stroke
				(width 0.508)
				(type default)
			)
			(layer "B.SilkS")
		)
		(fp_line
			(start 1.9558 -1.016)
			(end 1.9558 1.016)
			(stroke
				(width 0.1524)
				(type default)
			)
			(layer "B.SilkS")
		)
		(fp_line
			(start 1.9558 -0.5461)
			(end 1.4478 -0.0381)
			(stroke
				(width 0.1524)
				(type default)
			)
			(layer "B.SilkS")
		)
		(fp_line
			(start 1.9558 1.016)
			(end -1.0795 1.016)
			(stroke
				(width 0.1524)
				(type default)
			)
			(layer "B.SilkS")
		)
		(fp_poly
			(pts
				(xy 1.1557 -1.016) (xy 1.1557 1.016) (xy -1.1557 1.016) (xy -1.1557 -1.016)
			)
			(stroke
				(width 0)
				(type default)
			)
			(fill yes)
			(layer "B.SilkS")
		)
		(fp_rect
			(start 1.4986 2.4511)
			(end -1.4986 -2.4511)
			(stroke
				(width 0)
				(type default)
			)
			(fill no)
			(layer "B.CrtYd")
		)
		(fp_poly
			(pts
				(xy 2.032 3.302) (xy 2.032 -3.302) (xy -2.032 -3.302) (xy -2.032 -2.1209) (xy -1.4986 -2.1209) (xy -1.4986 -2.4511)
				(xy 1.4986 -2.4511) (xy 1.4986 2.4511) (xy -1.4986 2.4511) (xy -1.4986 -2.1082) (xy -2.032 -2.1082)
				(xy -2.032 3.302)
			)
			(stroke
				(width 0)
				(type default)
			)
			(fill no)
			(layer "B.CrtYd")
		)
		(fp_rect
			(start 2.032 3.302)
			(end -2.032 -3.302)
			(stroke
				(width 0)
				(type default)
			)
			(fill no)
			(layer "B.Fab")
		)
		(pad "1" smd rect
			(at 0.97536 2.05486 180)
			(size 0.3556 1.524)
			(layers "B.Cu" "B.Mask" "B.Paste")
			(net "P1V8_M2")
		)
		(pad "2" smd rect
			(at 0.32512 2.05486 180)
			(size 0.3556 1.524)
			(layers "B.Cu" "B.Mask" "B.Paste")
			(net "SMB_M2_ALT_R_N")
		)
		(pad "3" smd rect
			(at -0.32512 2.05486 180)
			(size 0.3556 1.524)
			(layers "B.Cu" "B.Mask" "B.Paste")
			(net "Net_6507")
		)
		(pad "4" smd rect
			(at -0.97536 2.05486 180)
			(size 0.3556 1.524)
			(layers "B.Cu" "B.Mask" "B.Paste")
			(net "GND")
		)
		(pad "5" smd rect
			(at -0.97536 -2.05486 180)
			(size 0.3556 1.524)
			(layers "B.Cu" "B.Mask" "B.Paste")
			(net "PD_SMB_M2_EN")
		)
		(pad "6" smd rect
			(at -0.32512 -2.05486 180)
			(size 0.3556 1.524)
			(layers "B.Cu" "B.Mask" "B.Paste")
			(net "Net_6506")
		)
		(pad "7" smd rect
			(at 0.32512 -2.05486 180)
			(size 0.3556 1.524)
			(layers "B.Cu" "B.Mask" "B.Paste")
			(net "IRQ_MEZZ_LAN_ALERT_N")
		)
		(pad "8" smd rect
			(at 0.97536 -2.05486 180)
			(size 0.3556 1.524)
			(layers "B.Cu" "B.Mask" "B.Paste")
			(net "P3V3_STBY")
		)
	)
	(footprint ""
		(layer "B.Cu")
		(at 26.896568 -154.559 180)
		(property "Reference" "C9L3"
			(at 0 0 0)
			(layer "B.SilkS")
			(hide yes)
			(effects
				(font
					(size 1.27 1.27)
				)
				(justify mirror)
			)
		)
		(property "Value" ""
			(at 0 0 0)
			(layer "B.Fab")
			(effects
				(font
					(size 1.27 1.27)
				)
				(justify mirror)
			)
		)
		(duplicate_pad_numbers_are_jumpers no)
		(fp_poly
			(pts
				(xy -0.3048 -0.1016) (xy -0.3048 0.9906) (xy 0.3048 0.9906) (xy 0.3048 -0.1016)
			)
			(stroke
				(width 0)
				(type default)
			)
			(fill no)
			(layer "B.CrtYd")
		)
		(fp_line
			(start 0.3048 0.9906)
			(end -0.3048 0.9906)
			(stroke
				(width 0.1)
				(type default)
			)
			(layer "B.Fab")
		)
		(fp_line
			(start 0.3048 -0.1016)
			(end 0.3048 0.9906)
			(stroke
				(width 0.1)
				(type default)
			)
			(layer "B.Fab")
		)
		(fp_line
			(start -0.3048 0.9906)
			(end -0.3048 -0.1016)
			(stroke
				(width 0.1)
				(type default)
			)
			(layer "B.Fab")
		)
		(fp_line
			(start -0.3048 -0.1016)
			(end 0.3048 -0.1016)
			(stroke
				(width 0.1)
				(type default)
			)
			(layer "B.Fab")
		)
		(pad "1" smd rect
			(at 0 0)
			(size 0.508 0.508)
			(layers "B.Cu" "B.Mask" "B.Paste")
			(net "M_M_CPU_VREF")
		)
		(pad "2" smd rect
			(at 0 0.889)
			(size 0.508 0.508)
			(layers "B.Cu" "B.Mask" "B.Paste")
			(net "GND")
		)
		(zone
			(layer "B.Cu")
			(hatch none 0.5)
			(connect_pads
				(clearance 0)
			)
			(min_thickness 0.25)
			(keepout
				(tracks not_allowed)
				(vias allowed)
				(pads allowed)
				(copperpour not_allowed)
				(footprints allowed)
			)
			(placement
				(enabled no)
				(sheetname "")
			)
			(fill
				(thermal_gap 0.5)
				(thermal_bridge_width 0.5)
				(island_removal_mode 0)
			)
			(polygon
				(pts
					(xy 26.642568 -155.194) (xy 27.150568 -155.194) (xy 27.150568 -154.813) (xy 26.642568 -154.813)
				)
			)
		)
		(zone
			(layer "B.Cu")
			(hatch none 0.5)
			(connect_pads
				(clearance 0)
			)
			(min_thickness 0.25)
			(keepout
				(tracks allowed)
				(vias not_allowed)
				(pads allowed)
				(copperpour not_allowed)
				(footprints allowed)
			)
			(placement
				(enabled no)
				(sheetname "")
			)
			(fill
				(thermal_gap 0.5)
				(thermal_bridge_width 0.5)
				(island_removal_mode 0)
			)
			(polygon
				(pts
					(xy 26.642568 -154.813) (xy 27.150568 -154.813) (xy 27.150568 -155.194) (xy 26.642568 -155.194)
				)
			)
		)
	)
)
